# T6G (Grand Teton) — schematic netlist excerpt (pin names and nets, part order shuffled) for the footprints in the layout excerpt that follows; sources: Cadence DE-HDL packaged netlist, KiCad conversion of 04192023_DAF0TMB3IC0_F0TG_MB_C_brd_V02_OCP.brd

C2642  Q_CAP  22UF 4V 20% X6S  pkg C0402  page 70 : A = PVDD11_S3_P0 ; B = GND
C1515  Q_CAP  0.1UF 16V 10% X7R  pkg C0402  page 173 : A = PVDD18_S5_P0 ; B = GND

(kicad_pcb
	(version 20260206)
	(generator "pcbnew")
	(generator_version "10.0")
	(general
		(thickness 1.6)
		(legacy_teardrops no)
	)
	(paper "A4")
	(title_block
		(title "04192023_DAF0TMB3IC0_F0TG_MB_C_brd_V02_OCP.brd")
		(comment 1 "Grand Teton / footprints 1266-1267 of 8354")
	)
	(layers
		(0 "F.Cu" signal "TOP")
		(4 "In1.Cu" signal "GND")
		(6 "In2.Cu" signal "IN1")
		(8 "In3.Cu" signal "GND1")
		(10 "In4.Cu" signal "IN2")
		(12 "In5.Cu" signal "GND2")
		(14 "In6.Cu" signal "IN3")
		(16 "In7.Cu" signal "GND3")
		(18 "In8.Cu" signal "VCC")
		(20 "In9.Cu" signal "VCC1")
		(22 "In10.Cu" signal "GND4")
		(24 "In11.Cu" signal "IN4")
		(26 "In12.Cu" signal "GND5")
		(28 "In13.Cu" signal "IN5")
		(30 "In14.Cu" signal "GND6")
		(32 "In15.Cu" signal "IN6")
		(34 "In16.Cu" signal "GND7")
		(2 "B.Cu" signal "BOTTOM")
		(9 "F.Adhes" user "F.Adhesive")
		(11 "B.Adhes" user "B.Adhesive")
		(13 "F.Paste" user "Package Geometry/Pastemask Top")
		(15 "B.Paste" user "Package Geometry/Pastemask Bottom")
		(5 "F.SilkS" user "Ref Des/Silkscreen Top")
		(7 "B.SilkS" user "Ref Des/Silkscreen Bottom")
		(1 "F.Mask" user "Board Geometry/Soldermask Top")
		(3 "B.Mask" user "Board Geometry/Soldermask Bottom")
		(17 "Dwgs.User" user "User.Drawings")
		(19 "Cmts.User" user "User.Comments")
		(21 "Eco1.User" user "User.Eco1")
		(23 "Eco2.User" user "User.Eco2")
		(25 "Edge.Cuts" user "Board Geometry/Outline")
		(27 "Margin" user)
		(31 "F.CrtYd" user "Package Geometry/Place Bound Top")
		(29 "B.CrtYd" user "Package Geometry/Place Bound Bottom")
		(35 "F.Fab" user "Ref Des/Assembly Top")
		(33 "B.Fab" user "Ref Des/Assembly Bottom")
	)
	(footprint ""
		(layer "F.Cu")
		(at 285.980886 -101.09708)
		(property "Reference" "C1515"
			(at 0 0 0)
			(layer "F.SilkS")
			(hide yes)
			(effects
				(font
					(size 1.27 1.27)
				)
			)
		)
		(property "Value" ""
			(at 0 0 0)
			(layer "F.Fab")
			(effects
				(font
					(size 1.27 1.27)
				)
			)
		)
		(duplicate_pad_numbers_are_jumpers no)
		(fp_line
			(start -0.7874 -0.4064)
			(end 0.7874 -0.4064)
			(stroke
				(width 0.1524)
				(type default)
			)
			(layer "F.SilkS")
		)
		(fp_line
			(start -0.7874 0.4064)
			(end -0.7874 -0.4064)
			(stroke
				(width 0.1524)
				(type default)
			)
			(layer "F.SilkS")
		)
		(fp_line
			(start 0.7874 -0.4064)
			(end 0.7874 0.4064)
			(stroke
				(width 0.1524)
				(type default)
			)
			(layer "F.SilkS")
		)
		(fp_line
			(start 0.7874 0.4064)
			(end -0.7874 0.4064)
			(stroke
				(width 0.1524)
				(type default)
			)
			(layer "F.SilkS")
		)
		(fp_line
			(start -0.67945 -0.305054)
			(end -0.12065 -0.305054)
			(stroke
				(width 0.1)
				(type default)
			)
			(layer "F.Fab")
		)
		(fp_line
			(start -0.67945 0.3048)
			(end -0.67945 -0.305054)
			(stroke
				(width 0.1)
				(type default)
			)
			(layer "F.Fab")
		)
		(fp_line
			(start -0.12065 -0.305054)
			(end -0.12065 -0.2794)
			(stroke
				(width 0.1)
				(type default)
			)
			(layer "F.Fab")
		)
		(fp_line
			(start -0.12065 -0.2794)
			(end 0.12065 -0.2794)
			(stroke
				(width 0.1)
				(type default)
			)
			(layer "F.Fab")
		)
		(fp_line
			(start -0.12065 0.2794)
			(end -0.12065 0.3048)
			(stroke
				(width 0.1)
				(type default)
			)
			(layer "F.Fab")
		)
		(fp_line
			(start -0.12065 0.3048)
			(end -0.67945 0.3048)
			(stroke
				(width 0.1)
				(type default)
			)
			(layer "F.Fab")
		)
		(fp_line
			(start 0.120396 0.2794)
			(end -0.12065 0.2794)
			(stroke
				(width 0.1)
				(type default)
			)
			(layer "F.Fab")
		)
		(fp_line
			(start 0.120396 0.3048)
			(end 0.120396 0.2794)
			(stroke
				(width 0.1)
				(type default)
			)
			(layer "F.Fab")
		)
		(fp_line
			(start 0.12065 -0.3048)
			(end 0.67945 -0.3048)
			(stroke
				(width 0.1)
				(type default)
			)
			(layer "F.Fab")
		)
		(fp_line
			(start 0.12065 -0.2794)
			(end 0.12065 -0.3048)
			(stroke
				(width 0.1)
				(type default)
			)
			(layer "F.Fab")
		)
		(fp_line
			(start 0.67945 -0.3048)
			(end 0.67945 0.3048)
			(stroke
				(width 0.1)
				(type default)
			)
			(layer "F.Fab")
		)
		(fp_line
			(start 0.67945 0.3048)
			(end 0.120396 0.3048)
			(stroke
				(width 0.1)
				(type default)
			)
			(layer "F.Fab")
		)
		(pad "1" smd circle
			(at -0.40005 0)
			(size 0 0)
			(layers "F.Cu" "F.Mask" "F.Paste")
			(net "PVDD18_S5_P0")
		)
		(pad "2" smd circle
			(at 0.40005 0)
			(size 0 0)
			(layers "F.Cu" "F.Mask" "F.Paste")
			(net "GND")
		)
	)
	(footprint ""
		(layer "F.Cu")
		(at 356.567232 -261.747762 -90)
		(property "Reference" "C2642"
			(at 0 0 270)
			(layer "F.SilkS")
			(hide yes)
			(effects
				(font
					(size 1.27 1.27)
				)
			)
		)
		(property "Value" ""
			(at 0 0 270)
			(layer "F.Fab")
			(effects
				(font
					(size 1.27 1.27)
				)
			)
		)
		(duplicate_pad_numbers_are_jumpers no)
		(fp_line
			(start -0.7874 0.4064)
			(end -0.7874 -0.4064)
			(stroke
				(width 0.1524)
				(type default)
			)
			(layer "F.SilkS")
		)
		(fp_line
			(start 0.7874 0.4064)
			(end -0.7874 0.4064)
			(stroke
				(width 0.1524)
				(type default)
			)
			(layer "F.SilkS")
		)
		(fp_line
			(start -0.7874 -0.4064)
			(end 0.7874 -0.4064)
			(stroke
				(width 0.1524)
				(type default)
			)
			(layer "F.SilkS")
		)
		(fp_line
			(start 0.7874 -0.4064)
			(end 0.7874 0.4064)
			(stroke
				(width 0.1524)
				(type default)
			)
			(layer "F.SilkS")
		)
		(fp_line
			(start -0.67945 0.3048)
			(end -0.67945 -0.305054)
			(stroke
				(width 0.1)
				(type default)
			)
			(layer "F.Fab")
		)
		(fp_line
			(start -0.12065 0.3048)
			(end -0.67945 0.3048)
			(stroke
				(width 0.1)
				(type default)
			)
			(layer "F.Fab")
		)
		(fp_line
			(start 0.120396 0.3048)
			(end 0.120396 0.2794)
			(stroke
				(width 0.1)
				(type default)
			)
			(layer "F.Fab")
		)
		(fp_line
			(start 0.67945 0.3048)
			(end 0.120396 0.3048)
			(stroke
				(width 0.1)
				(type default)
			)
			(layer "F.Fab")
		)
		(fp_line
			(start -0.12065 0.2794)
			(end -0.12065 0.3048)
			(stroke
				(width 0.1)
				(type default)
			)
			(layer "F.Fab")
		)
		(fp_line
			(start 0.120396 0.2794)
			(end -0.12065 0.2794)
			(stroke
				(width 0.1)
				(type default)
			)
			(layer "F.Fab")
		)
		(fp_line
			(start -0.12065 -0.2794)
			(end 0.12065 -0.2794)
			(stroke
				(width 0.1)
				(type default)
			)
			(layer "F.Fab")
		)
		(fp_line
			(start 0.12065 -0.2794)
			(end 0.12065 -0.3048)
			(stroke
				(width 0.1)
				(type default)
			)
			(layer "F.Fab")
		)
		(fp_line
			(start 0.12065 -0.3048)
			(end 0.67945 -0.3048)
			(stroke
				(width 0.1)
				(type default)
			)
			(layer "F.Fab")
		)
		(fp_line
			(start 0.67945 -0.3048)
			(end 0.67945 0.3048)
			(stroke
				(width 0.1)
				(type default)
			)
			(layer "F.Fab")
		)
		(fp_line
			(start -0.67945 -0.305054)
			(end -0.12065 -0.305054)
			(stroke
				(width 0.1)
				(type default)
			)
			(layer "F.Fab")
		)
		(fp_line
			(start -0.12065 -0.305054)
			(end -0.12065 -0.2794)
			(stroke
				(width 0.1)
				(type default)
			)
			(layer "F.Fab")
		)
		(pad "1" smd circle
			(at -0.40005 0 270)
			(size 0 0)
			(layers "F.Cu" "F.Mask" "F.Paste")
			(net "PVDD11_S3_P0")
		)
		(pad "2" smd circle
			(at 0.40005 0 270)
			(size 0 0)
			(layers "F.Cu" "F.Mask" "F.Paste")
			(net "GND")
		)
	)
)
